(kicad_pcb
	(version 20260206)
	(generator "pcbnew")
	(generator_version "10.0")
	(general
		(thickness 1.6)
		(legacy_teardrops no)
	)
	(paper "A4")
	(title_block
		(title "Bryce Canyon_F.DPB_16315-1-OCP.brd")
		(comment 1 "Bryce Canyon / footprints 233-239 of 2223")
	)
	(layers
		(0 "F.Cu" signal "TOP")
		(4 "In1.Cu" signal "L2GND")
		(6 "In2.Cu" signal "L3")
		(8 "In3.Cu" signal "L4GND")
		(10 "In4.Cu" signal "L5")
		(12 "In5.Cu" signal "L6VCC")
		(14 "In6.Cu" signal "L7VCC")
		(16 "In7.Cu" signal "L8")
		(18 "In8.Cu" signal "L9GND")
		(20 "In9.Cu" signal "L10")
		(22 "In10.Cu" signal "L11GND")
		(2 "B.Cu" signal "BOTTOM")
		(9 "F.Adhes" user "F.Adhesive")
		(11 "B.Adhes" user "B.Adhesive")
		(13 "F.Paste" user "Package Geometry/Pastemask Top")
		(15 "B.Paste" user "Package Geometry/Pastemask Bottom")
		(5 "F.SilkS" user "Ref Des/Silkscreen Top")
		(7 "B.SilkS" user "Ref Des/Silkscreen Bottom")
		(1 "F.Mask" user "Board Geometry/Soldermask Top")
		(3 "B.Mask" user "Board Geometry/Soldermask Bottom")
		(17 "Dwgs.User" user "User.Drawings")
		(19 "Cmts.User" user "User.Comments")
		(21 "Eco1.User" user "User.Eco1")
		(23 "Eco2.User" user "User.Eco2")
		(25 "Edge.Cuts" user "Board Geometry/Outline")
		(27 "Margin" user)
		(31 "F.CrtYd" user "Package Geometry/Place Bound Top")
		(29 "B.CrtYd" user "Package Geometry/Place Bound Bottom")
		(35 "F.Fab" user "Ref Des/Assembly Top")
		(33 "B.Fab" user "Ref Des/Assembly Bottom")
	)
	(footprint ""
		(layer "F.Cu")
		(at 24.240998 -189.462918 180)
		(property "Reference" "C203"
			(at 0 0 180)
			(layer "F.SilkS")
			(hide yes)
			(effects
				(font
					(size 1.27 1.27)
				)
			)
		)
		(property "Value" "SC1U25V3KX-GP"
			(at 0 -2.8194 180)
			(unlocked yes)
			(layer "F.Fab")
			(hide yes)
			(effects
				(font
					(size 1.016 1.016)
					(thickness 0.1524)
				)
			)
		)
		(property "Device Type" "C603H36"
			(at 0 -4.3434 180)
			(unlocked yes)
			(layer "F.Fab")
			(hide yes)
			(effects
				(font
					(size 1.016 1.016)
					(thickness 0.1524)
				)
			)
		)
		(duplicate_pad_numbers_are_jumpers no)
		(fp_line
			(start 0.508 0)
			(end -0.508 0)
			(stroke
				(width 0.2032)
				(type default)
			)
			(layer "F.SilkS")
		)
		(fp_rect
			(start -0.5842 1.3335)
			(end 0.5842 -1.3335)
			(stroke
				(width 0)
				(type default)
			)
			(fill no)
			(layer "F.CrtYd")
		)
		(fp_rect
			(start -0.5842 1.3335)
			(end 0.5842 -1.3335)
			(stroke
				(width 0)
				(type default)
			)
			(fill no)
			(layer "F.Fab")
		)
		(pad "1" smd custom
			(at 0 -0.762 180)
			(size 0.2159 0.2159)
			(layers "F.Cu" "F.Mask" "F.Paste")
			(net "P12V_HDD12")
			(options
				(clearance outline)
				(anchor circle)
			)
			(primitives
				(gr_poly
					(pts
						(arc
							(start -0.3302 -0.4318)
							(mid -0.402042 -0.402042)
							(end -0.4318 -0.3302)
						)
						(arc
							(start -0.4318 0.3302)
							(mid -0.402042 0.402042)
							(end -0.3302 0.4318)
						)
						(arc
							(start 0.3302 0.4318)
							(mid 0.402042 0.402042)
							(end 0.4318 0.3302)
						)
						(arc
							(start 0.4318 -0.3302)
							(mid 0.402042 -0.402042)
							(end 0.3302 -0.4318)
						)
					)
					(width 0)
					(fill yes)
				)
			)
		)
		(pad "2" smd custom
			(at 0 0.762 180)
			(size 0.2159 0.2159)
			(layers "F.Cu" "F.Mask" "F.Paste")
			(net "GND")
			(options
				(clearance outline)
				(anchor circle)
			)
			(primitives
				(gr_poly
					(pts
						(arc
							(start -0.3302 -0.4318)
							(mid -0.402042 -0.402042)
							(end -0.4318 -0.3302)
						)
						(arc
							(start -0.4318 0.3302)
							(mid -0.402042 0.402042)
							(end -0.3302 0.4318)
						)
						(arc
							(start 0.3302 0.4318)
							(mid 0.402042 0.402042)
							(end 0.4318 0.3302)
						)
						(arc
							(start 0.4318 -0.3302)
							(mid 0.402042 -0.402042)
							(end 0.3302 -0.4318)
						)
					)
					(width 0)
					(fill yes)
				)
			)
		)
	)
	(footprint ""
		(layer "F.Cu")
		(at 263.9314 -230.3018)
		(property "Reference" "R89"
			(at 0 0 0)
			(layer "F.SilkS")
			(hide yes)
			(effects
				(font
					(size 1.27 1.27)
				)
			)
		)
		(property "Value" "4K7R2F-GP"
			(at 0.064008 -3.993896 0)
			(unlocked yes)
			(layer "F.Fab")
			(hide yes)
			(effects
				(font
					(size 1.016 1.016)
					(thickness 0.1524)
				)
			)
		)
		(property "Device Type" "R402H16"
			(at 0.064008 -5.517896 0)
			(unlocked yes)
			(layer "F.Fab")
			(hide yes)
			(effects
				(font
					(size 1.016 1.016)
					(thickness 0.1524)
				)
			)
		)
		(duplicate_pad_numbers_are_jumpers no)
		(fp_line
			(start -0.508 -0.9398)
			(end -0.508 0.9398)
			(stroke
				(width 0.1524)
				(type default)
			)
			(layer "F.SilkS")
		)
		(fp_line
			(start 0.508 -0.9398)
			(end -0.508 -0.9398)
			(stroke
				(width 0.1524)
				(type default)
			)
			(layer "F.SilkS")
		)
		(fp_rect
			(start -0.508 0.9398)
			(end 0.508 -0.9398)
			(stroke
				(width 0)
				(type default)
			)
			(fill no)
			(layer "F.CrtYd")
		)
		(fp_rect
			(start -0.508 0.9398)
			(end 0.508 -0.9398)
			(stroke
				(width 0)
				(type default)
			)
			(fill no)
			(layer "F.Fab")
		)
		(pad "1" smd custom
			(at 0 -0.4445)
			(size 0.1397 0.1397)
			(layers "F.Cu" "F.Mask" "F.Paste")
			(net "IO_EXP3_A0")
			(options
				(clearance outline)
				(anchor circle)
			)
			(primitives
				(gr_poly
					(pts
						(arc
							(start -0.1778 -0.2794)
							(mid -0.249642 -0.249642)
							(end -0.2794 -0.1778)
						)
						(arc
							(start -0.2794 0.1778)
							(mid -0.249642 0.249642)
							(end -0.1778 0.2794)
						)
						(arc
							(start 0.1778 0.2794)
							(mid 0.249642 0.249642)
							(end 0.2794 0.1778)
						)
						(arc
							(start 0.2794 -0.1778)
							(mid 0.249642 -0.249642)
							(end 0.1778 -0.2794)
						)
					)
					(width 0)
					(fill yes)
				)
			)
		)
		(pad "2" smd custom
			(at 0 0.4445)
			(size 0.1397 0.1397)
			(layers "F.Cu" "F.Mask" "F.Paste")
			(net "GND")
			(options
				(clearance outline)
				(anchor circle)
			)
			(primitives
				(gr_poly
					(pts
						(arc
							(start -0.1778 -0.2794)
							(mid -0.249642 -0.249642)
							(end -0.2794 -0.1778)
						)
						(arc
							(start -0.2794 0.1778)
							(mid -0.249642 0.249642)
							(end -0.1778 0.2794)
						)
						(arc
							(start 0.1778 0.2794)
							(mid 0.249642 0.249642)
							(end 0.2794 0.1778)
						)
						(arc
							(start 0.2794 -0.1778)
							(mid 0.249642 -0.249642)
							(end 0.1778 -0.2794)
						)
					)
					(width 0)
					(fill yes)
				)
			)
		)
	)
	(footprint ""
		(layer "F.Cu")
		(at 431.454052 -292.016942)
		(property "Reference" "Q56"
			(at 0 0 0)
			(layer "F.SilkS")
			(hide yes)
			(effects
				(font
					(size 1.27 1.27)
				)
			)
		)
		(property "Value" "AO4407AL-GP"
			(at -3.707384 -1.5367 0)
			(unlocked yes)
			(layer "F.Fab")
			(hide yes)
			(effects
				(font
					(size 1.016 1.016)
					(thickness 0.1524)
				)
			)
		)
		(property "Device Type" "SOIC8H69"
			(at -3.707384 -3.0607 0)
			(unlocked yes)
			(layer "F.Fab")
			(hide yes)
			(effects
				(font
					(size 1.016 1.016)
					(thickness 0.1524)
				)
			)
		)
		(duplicate_pad_numbers_are_jumpers no)
		(fp_line
			(start -2.7432 -1.4224)
			(end -2.7432 1.4224)
			(stroke
				(width 0.1524)
				(type default)
			)
			(layer "F.SilkS")
		)
		(fp_line
			(start -2.7432 1.4224)
			(end -2.6416 1.4224)
			(stroke
				(width 0.1524)
				(type default)
			)
			(layer "F.SilkS")
		)
		(fp_line
			(start -2.7432 1.4224)
			(end 2.1336 1.4224)
			(stroke
				(width 0.1524)
				(type default)
			)
			(layer "F.SilkS")
		)
		(fp_line
			(start -2.7178 -0.508)
			(end -2.1844 -0.0508)
			(stroke
				(width 0.1524)
				(type default)
			)
			(layer "F.SilkS")
		)
		(fp_line
			(start -2.6289 3.4417)
			(end -2.6289 1.4732)
			(stroke
				(width 0.381)
				(type default)
			)
			(layer "F.SilkS")
		)
		(fp_line
			(start -2.1844 -0.0508)
			(end -2.7178 0.508)
			(stroke
				(width 0.1524)
				(type default)
			)
			(layer "F.SilkS")
		)
		(fp_line
			(start 2.1336 -1.4224)
			(end -2.7432 -1.4224)
			(stroke
				(width 0.1524)
				(type default)
			)
			(layer "F.SilkS")
		)
		(fp_line
			(start 2.1336 1.4224)
			(end 2.1336 -1.4224)
			(stroke
				(width 0.1524)
				(type default)
			)
			(layer "F.SilkS")
		)
		(fp_poly
			(pts
				(xy -2.2098 -1.4224) (xy -2.2098 1.4224) (xy 2.2098 1.4224) (xy 2.2098 -1.4224)
			)
			(stroke
				(width 0)
				(type default)
			)
			(fill yes)
			(layer "F.SilkS")
		)
		(fp_rect
			(start -2.450084 2.999994)
			(end 2.450084 -2.999994)
			(stroke
				(width 0)
				(type default)
			)
			(fill no)
			(layer "F.CrtYd")
		)
		(fp_poly
			(pts
				(xy -2.8194 3.6322) (xy -2.8194 -3.6322) (xy 2.8194 -3.6322) (xy 2.8194 1.18364) (xy 2.450084 1.18364)
				(xy 2.450084 -2.999994) (xy -2.450084 -2.999994) (xy -2.450084 2.999994) (xy 2.450084 2.999994)
				(xy 2.450084 1.18618) (xy 2.8194 1.18618) (xy 2.8194 3.6322)
			)
			(stroke
				(width 0)
				(type default)
			)
			(fill no)
			(layer "F.CrtYd")
		)
		(fp_rect
			(start -2.8194 3.6322)
			(end 2.8194 -3.6322)
			(stroke
				(width 0)
				(type default)
			)
			(fill no)
			(layer "F.Fab")
		)
		(pad "1" smd rect
			(at -1.905 2.54)
			(size 0.635 1.651)
			(layers "F.Cu" "F.Mask" "F.Paste")
			(net "P12V_A")
		)
		(pad "2" smd rect
			(at -0.635 2.54)
			(size 0.635 1.651)
			(layers "F.Cu" "F.Mask" "F.Paste")
			(net "P12V_A")
		)
		(pad "3" smd rect
			(at 0.635 2.54)
			(size 0.635 1.651)
			(layers "F.Cu" "F.Mask" "F.Paste")
			(net "P12V_A")
		)
		(pad "4" smd rect
			(at 1.905 2.54)
			(size 0.635 1.651)
			(layers "F.Cu" "F.Mask" "F.Paste")
			(net "SW_HDD_N9")
		)
		(pad "5" smd rect
			(at 1.905 -2.54)
			(size 0.635 1.651)
			(layers "F.Cu" "F.Mask" "F.Paste")
			(net "P12V_HDD9")
		)
		(pad "6" smd rect
			(at 0.635 -2.54)
			(size 0.635 1.651)
			(layers "F.Cu" "F.Mask" "F.Paste")
			(net "P12V_HDD9")
		)
		(pad "7" smd rect
			(at -0.635 -2.54)
			(size 0.635 1.651)
			(layers "F.Cu" "F.Mask" "F.Paste")
			(net "P12V_HDD9")
		)
		(pad "8" smd rect
			(at -1.905 -2.54)
			(size 0.635 1.651)
			(layers "F.Cu" "F.Mask" "F.Paste")
			(net "P12V_HDD9")
		)
	)
	(footprint ""
		(layer "F.Cu")
		(at 359.681526 -132.196078 90)
		(property "Reference" "R1097"
			(at 0 0 90)
			(layer "F.SilkS")
			(hide yes)
			(effects
				(font
					(size 1.27 1.27)
				)
			)
		)
		(property "Value" "49K9R2F-L-GP"
			(at 0.064008 -3.993896 90)
			(unlocked yes)
			(layer "F.Fab")
			(hide yes)
			(effects
				(font
					(size 1.016 1.016)
					(thickness 0.1524)
				)
			)
		)
		(property "Device Type" "R402H16"
			(at 0.064008 -5.517896 90)
			(unlocked yes)
			(layer "F.Fab")
			(hide yes)
			(effects
				(font
					(size 1.016 1.016)
					(thickness 0.1524)
				)
			)
		)
		(duplicate_pad_numbers_are_jumpers no)
		(fp_line
			(start 0.508 -0.9398)
			(end -0.508 -0.9398)
			(stroke
				(width 0.1524)
				(type default)
			)
			(layer "F.SilkS")
		)
		(fp_line
			(start -0.508 -0.9398)
			(end -0.508 0.9398)
			(stroke
				(width 0.1524)
				(type default)
			)
			(layer "F.SilkS")
		)
		(fp_rect
			(start -0.508 0.9398)
			(end 0.508 -0.9398)
			(stroke
				(width 0)
				(type default)
			)
			(fill no)
			(layer "F.CrtYd")
		)
		(fp_rect
			(start -0.508 0.9398)
			(end 0.508 -0.9398)
			(stroke
				(width 0)
				(type default)
			)
			(fill no)
			(layer "F.Fab")
		)
		(pad "1" smd custom
			(at 0 -0.4445 90)
			(size 0.1397 0.1397)
			(layers "F.Cu" "F.Mask" "F.Paste")
			(net "P12V_B")
			(options
				(clearance outline)
				(anchor circle)
			)
			(primitives
				(gr_poly
					(pts
						(arc
							(start -0.1778 -0.2794)
							(mid -0.249642 -0.249642)
							(end -0.2794 -0.1778)
						)
						(arc
							(start -0.2794 0.1778)
							(mid -0.249642 0.249642)
							(end -0.1778 0.2794)
						)
						(arc
							(start 0.1778 0.2794)
							(mid 0.249642 0.249642)
							(end 0.2794 0.1778)
						)
						(arc
							(start 0.2794 -0.1778)
							(mid 0.249642 -0.249642)
							(end 0.1778 -0.2794)
						)
					)
					(width 0)
					(fill yes)
				)
			)
		)
		(pad "2" smd custom
			(at 0 0.4445 90)
			(size 0.1397 0.1397)
			(layers "F.Cu" "F.Mask" "F.Paste")
			(net "MB1_CM_OV_R")
			(options
				(clearance outline)
				(anchor circle)
			)
			(primitives
				(gr_poly
					(pts
						(arc
							(start -0.1778 -0.2794)
							(mid -0.249642 -0.249642)
							(end -0.2794 -0.1778)
						)
						(arc
							(start -0.2794 0.1778)
							(mid -0.249642 0.249642)
							(end -0.1778 0.2794)
						)
						(arc
							(start 0.1778 0.2794)
							(mid 0.249642 0.249642)
							(end 0.2794 0.1778)
						)
						(arc
							(start 0.2794 -0.1778)
							(mid 0.249642 -0.249642)
							(end 0.1778 -0.2794)
						)
					)
					(width 0)
					(fill yes)
				)
			)
		)
	)
	(footprint ""
		(layer "F.Cu")
		(at 174.117 -162.157918 180)
		(property "Reference" "R537"
			(at 0 0 180)
			(layer "F.SilkS")
			(hide yes)
			(effects
				(font
					(size 1.27 1.27)
				)
			)
		)
		(property "Value" "200KR2F-L-GP"
			(at 0.064008 -3.993896 180)
			(unlocked yes)
			(layer "F.Fab")
			(hide yes)
			(effects
				(font
					(size 1.016 1.016)
					(thickness 0.1524)
				)
			)
		)
		(property "Device Type" "R402H16"
			(at 0.064008 -5.517896 180)
			(unlocked yes)
			(layer "F.Fab")
			(hide yes)
			(effects
				(font
					(size 1.016 1.016)
					(thickness 0.1524)
				)
			)
		)
		(duplicate_pad_numbers_are_jumpers no)
		(fp_line
			(start 0.508 -0.9398)
			(end -0.508 -0.9398)
			(stroke
				(width 0.1524)
				(type default)
			)
			(layer "F.SilkS")
		)
		(fp_line
			(start -0.508 -0.9398)
			(end -0.508 0.9398)
			(stroke
				(width 0.1524)
				(type default)
			)
			(layer "F.SilkS")
		)
		(fp_rect
			(start -0.508 0.9398)
			(end 0.508 -0.9398)
			(stroke
				(width 0)
				(type default)
			)
			(fill no)
			(layer "F.CrtYd")
		)
		(fp_rect
			(start -0.508 0.9398)
			(end 0.508 -0.9398)
			(stroke
				(width 0)
				(type default)
			)
			(fill no)
			(layer "F.Fab")
		)
		(pad "1" smd custom
			(at 0 -0.4445 180)
			(size 0.1397 0.1397)
			(layers "F.Cu" "F.Mask" "F.Paste")
			(net "SW_HDD_R17")
			(options
				(clearance outline)
				(anchor circle)
			)
			(primitives
				(gr_poly
					(pts
						(arc
							(start -0.1778 -0.2794)
							(mid -0.249642 -0.249642)
							(end -0.2794 -0.1778)
						)
						(arc
							(start -0.2794 0.1778)
							(mid -0.249642 0.249642)
							(end -0.1778 0.2794)
						)
						(arc
							(start 0.1778 0.2794)
							(mid 0.249642 0.249642)
							(end 0.2794 0.1778)
						)
						(arc
							(start 0.2794 -0.1778)
							(mid 0.249642 -0.249642)
							(end 0.1778 -0.2794)
						)
					)
					(width 0)
					(fill yes)
				)
			)
		)
		(pad "2" smd custom
			(at 0 0.4445 180)
			(size 0.1397 0.1397)
			(layers "F.Cu" "F.Mask" "F.Paste")
			(net "SW_HDD_N17")
			(options
				(clearance outline)
				(anchor circle)
			)
			(primitives
				(gr_poly
					(pts
						(arc
							(start -0.1778 -0.2794)
							(mid -0.249642 -0.249642)
							(end -0.2794 -0.1778)
						)
						(arc
							(start -0.2794 0.1778)
							(mid -0.249642 0.249642)
							(end -0.1778 0.2794)
						)
						(arc
							(start 0.1778 0.2794)
							(mid 0.249642 0.249642)
							(end 0.2794 0.1778)
						)
						(arc
							(start 0.2794 -0.1778)
							(mid 0.249642 -0.249642)
							(end 0.1778 -0.2794)
						)
					)
					(width 0)
					(fill yes)
				)
			)
		)
	)
	(footprint ""
		(layer "F.Cu")
		(at 181.483 -62.270894)
		(property "Reference" "R796"
			(at 0 0 0)
			(layer "F.SilkS")
			(hide yes)
			(effects
				(font
					(size 1.27 1.27)
				)
			)
		)
		(property "Value" "2R6F-GP"
			(at -0.0508 -4.8514 0)
			(unlocked yes)
			(layer "F.Fab")
			(hide yes)
			(effects
				(font
					(size 1.016 1.016)
					(thickness 0.1524)
				)
			)
		)
		(property "Device Type" "R1206H26"
			(at 0 -6.3754 0)
			(unlocked yes)
			(layer "F.Fab")
			(hide yes)
			(effects
				(font
					(size 1.016 1.016)
					(thickness 0.1524)
				)
			)
		)
		(duplicate_pad_numbers_are_jumpers no)
		(fp_line
			(start -1.016 -2.2352)
			(end 1.016 -2.2352)
			(stroke
				(width 0.1524)
				(type default)
			)
			(layer "F.SilkS")
		)
		(fp_line
			(start -1.016 2.2352)
			(end -1.016 -2.2352)
			(stroke
				(width 0.1524)
				(type default)
			)
			(layer "F.SilkS")
		)
		(fp_line
			(start 1.016 -2.2352)
			(end 1.016 2.2352)
			(stroke
				(width 0.1524)
				(type default)
			)
			(layer "F.SilkS")
		)
		(fp_line
			(start 1.016 2.2352)
			(end -1.016 2.2352)
			(stroke
				(width 0.1524)
				(type default)
			)
			(layer "F.SilkS")
		)
		(fp_rect
			(start -1.0922 2.3114)
			(end 1.0922 -2.3114)
			(stroke
				(width 0)
				(type default)
			)
			(fill no)
			(layer "F.CrtYd")
		)
		(fp_poly
			(pts
				(xy -1.0922 -2.3114) (xy 1.0922 -2.3114) (xy 1.0922 2.3114) (xy -1.0922 2.3114)
			)
			(stroke
				(width 0)
				(type default)
			)
			(fill no)
			(layer "F.Fab")
		)
		(pad "1" smd rect
			(at 0 -1.397)
			(size 1.651 1.27)
			(layers "F.Cu" "F.Mask" "F.Paste")
			(net "P5V_HDD29")
		)
		(pad "2" smd rect
			(at 0 1.397)
			(size 1.651 1.27)
			(layers "F.Cu" "F.Mask" "F.Paste")
			(net "5V_PRE_29")
		)
	)
	(footprint ""
		(layer "F.Cu")
		(at 242.7478 -260.5532 180)
		(property "Reference" "R41"
			(at 0 0 180)
			(layer "F.SilkS")
			(hide yes)
			(effects
				(font
					(size 1.27 1.27)
				)
			)
		)
		(property "Value" "4K7R2F-GP"
			(at 0.064008 -3.993896 180)
			(unlocked yes)
			(layer "F.Fab")
			(hide yes)
			(effects
				(font
					(size 1.016 1.016)
					(thickness 0.1524)
				)
			)
		)
		(property "Device Type" "R402H16"
			(at 0.064008 -5.517896 180)
			(unlocked yes)
			(layer "F.Fab")
			(hide yes)
			(effects
				(font
					(size 1.016 1.016)
					(thickness 0.1524)
				)
			)
		)
		(duplicate_pad_numbers_are_jumpers no)
		(fp_line
			(start 0.508 -0.9398)
			(end -0.508 -0.9398)
			(stroke
				(width 0.1524)
				(type default)
			)
			(layer "F.SilkS")
		)
		(fp_line
			(start -0.508 -0.9398)
			(end -0.508 0.9398)
			(stroke
				(width 0.1524)
				(type default)
			)
			(layer "F.SilkS")
		)
		(fp_rect
			(start -0.508 0.9398)
			(end 0.508 -0.9398)
			(stroke
				(width 0)
				(type default)
			)
			(fill no)
			(layer "F.CrtYd")
		)
		(fp_rect
			(start -0.508 0.9398)
			(end 0.508 -0.9398)
			(stroke
				(width 0)
				(type default)
			)
			(fill no)
			(layer "F.Fab")
		)
		(pad "1" smd custom
			(at 0 -0.4445 180)
			(size 0.1397 0.1397)
			(layers "F.Cu" "F.Mask" "F.Paste")
			(net "IO_EXP5_A0")
			(options
				(clearance outline)
				(anchor circle)
			)
			(primitives
				(gr_poly
					(pts
						(arc
							(start -0.1778 -0.2794)
							(mid -0.249642 -0.249642)
							(end -0.2794 -0.1778)
						)
						(arc
							(start -0.2794 0.1778)
							(mid -0.249642 0.249642)
							(end -0.1778 0.2794)
						)
						(arc
							(start 0.1778 0.2794)
							(mid 0.249642 0.249642)
							(end 0.2794 0.1778)
						)
						(arc
							(start 0.2794 -0.1778)
							(mid 0.249642 -0.249642)
							(end 0.1778 -0.2794)
						)
					)
					(width 0)
					(fill yes)
				)
			)
		)
		(pad "2" smd custom
			(at 0 0.4445 180)
			(size 0.1397 0.1397)
			(layers "F.Cu" "F.Mask" "F.Paste")
			(net "GND")
			(options
				(clearance outline)
				(anchor circle)
			)
			(primitives
				(gr_poly
					(pts
						(arc
							(start -0.1778 -0.2794)
							(mid -0.249642 -0.249642)
							(end -0.2794 -0.1778)
						)
						(arc
							(start -0.2794 0.1778)
							(mid -0.249642 0.249642)
							(end -0.1778 0.2794)
						)
						(arc
							(start 0.1778 0.2794)
							(mid 0.249642 0.249642)
							(end 0.2794 0.1778)
						)
						(arc
							(start 0.2794 -0.1778)
							(mid 0.249642 -0.249642)
							(end 0.1778 -0.2794)
						)
					)
					(width 0)
					(fill yes)
				)
			)
		)
	)
)
